(kicad_pcb
	(version 20260206)
	(generator "pcbnew")
	(generator_version "10.0")
	(general
		(thickness 1.6)
		(legacy_teardrops no)
	)
	(paper "A4")
	(title_block
		(title "v1-pdb — T6M_PDB_D_0927_0900.brd")
		(comment 1 "Open CloudServer (Microsoft) / footprints 35-44 of 321")
	)
	(layers
		(0 "F.Cu" signal "TOP")
		(4 "In1.Cu" signal "GND")
		(6 "In2.Cu" signal "IN1")
		(8 "In3.Cu" signal "VCC")
		(10 "In4.Cu" signal "VCC1")
		(12 "In5.Cu" signal "IN2")
		(14 "In6.Cu" signal "GND1")
		(2 "B.Cu" signal "BOTTOM")
		(9 "F.Adhes" user "F.Adhesive")
		(11 "B.Adhes" user "B.Adhesive")
		(13 "F.Paste" user "Package Geometry/Pastemask Top")
		(15 "B.Paste" user "Package Geometry/Pastemask Bottom")
		(5 "F.SilkS" user "Ref Des/Silkscreen Top")
		(7 "B.SilkS" user "Ref Des/Silkscreen Bottom")
		(1 "F.Mask" user "Board Geometry/Soldermask Top")
		(3 "B.Mask" user "Board Geometry/Soldermask Bottom")
		(17 "Dwgs.User" user "User.Drawings")
		(19 "Cmts.User" user "User.Comments")
		(21 "Eco1.User" user "User.Eco1")
		(23 "Eco2.User" user "User.Eco2")
		(25 "Edge.Cuts" user "Board Geometry/Outline")
		(27 "Margin" user)
		(31 "F.CrtYd" user "Package Geometry/Place Bound Top")
		(29 "B.CrtYd" user "Package Geometry/Place Bound Bottom")
		(35 "F.Fab" user "Ref Des/Assembly Top")
		(33 "B.Fab" user "Ref Des/Assembly Bottom")
	)
	(footprint ""
		(layer "F.Cu")
		(at 46.365922 -257.889502 180)
		(property "Reference" "R107"
			(at -1.032002 -0.406908 0)
			(unlocked yes)
			(layer "F.SilkS")
			(effects
				(font
					(size 0.7874 0.5842)
					(thickness 0.1524)
				)
				(justify left)
			)
		)
		(property "Value" ""
			(at 0 0 180)
			(layer "F.Fab")
			(effects
				(font
					(size 1.27 1.27)
				)
			)
		)
		(duplicate_pad_numbers_are_jumpers no)
		(fp_line
			(start 0.7874 0.4064)
			(end -0.7874 0.4064)
			(stroke
				(width 0.1524)
				(type default)
			)
			(layer "F.SilkS")
		)
		(fp_line
			(start 0.7874 -0.4064)
			(end 0.7874 0.4064)
			(stroke
				(width 0.1524)
				(type default)
			)
			(layer "F.SilkS")
		)
		(fp_line
			(start -0.7874 0.4064)
			(end -0.7874 -0.4064)
			(stroke
				(width 0.1524)
				(type default)
			)
			(layer "F.SilkS")
		)
		(fp_line
			(start -0.7874 -0.4064)
			(end 0.7874 -0.4064)
			(stroke
				(width 0.1524)
				(type default)
			)
			(layer "F.SilkS")
		)
		(fp_poly
			(pts
				(xy -0.508 0.2794) (xy -0.508 0.2286) (xy -0.635 0.2286) (xy -0.635 -0.254) (xy -0.5334 -0.254)
				(xy -0.5334 -0.2794) (xy 0.5334 -0.2794) (xy 0.5334 -0.254) (xy 0.635 -0.254) (xy 0.635 0.254) (xy 0.5334 0.254)
				(xy 0.5334 0.2794)
			)
			(stroke
				(width 0)
				(type default)
			)
			(fill no)
			(layer "F.CrtYd")
		)
		(pad "1" smd rect
			(at 0.40005 0 180)
			(size 0.4572 0.508)
			(layers "F.Cu" "F.Mask" "F.Paste")
			(net "PSU4_REMOTE_R_N")
		)
		(pad "2" smd rect
			(at -0.40005 0 180)
			(size 0.4572 0.508)
			(layers "F.Cu" "F.Mask" "F.Paste")
			(net "GND")
		)
	)
	(footprint ""
		(layer "F.Cu")
		(at 75.059286 -149.113748 -90)
		(property "Reference" "C24"
			(at -2.638552 0.03937 90)
			(unlocked yes)
			(layer "F.SilkS")
			(effects
				(font
					(size 0.7874 0.5842)
					(thickness 0.1524)
				)
				(justify left)
			)
		)
		(property "Value" ""
			(at 0 0 270)
			(layer "F.Fab")
			(effects
				(font
					(size 1.27 1.27)
				)
			)
		)
		(duplicate_pad_numbers_are_jumpers no)
		(fp_line
			(start -0.7874 0.4064)
			(end -0.7874 -0.4064)
			(stroke
				(width 0.1524)
				(type default)
			)
			(layer "F.SilkS")
		)
		(fp_line
			(start 0.7874 0.4064)
			(end -0.7874 0.4064)
			(stroke
				(width 0.1524)
				(type default)
			)
			(layer "F.SilkS")
		)
		(fp_line
			(start 0 0.381)
			(end 0 -0.381)
			(stroke
				(width 0.1524)
				(type default)
			)
			(layer "F.SilkS")
		)
		(fp_line
			(start -0.7874 -0.4064)
			(end 0.7874 -0.4064)
			(stroke
				(width 0.1524)
				(type default)
			)
			(layer "F.SilkS")
		)
		(fp_line
			(start 0.7874 -0.4064)
			(end 0.7874 0.4064)
			(stroke
				(width 0.1524)
				(type default)
			)
			(layer "F.SilkS")
		)
		(fp_poly
			(pts
				(xy -0.5334 0.254) (xy -0.635 0.254) (xy -0.635 0.2286) (xy -0.635 -0.254) (xy -0.5334 -0.254) (xy -0.5334 -0.2794)
				(xy 0.5334 -0.2794) (xy 0.5334 -0.254) (xy 0.635 -0.254) (xy 0.635 0.254) (xy 0.5334 0.254) (xy 0.5334 0.2794)
				(xy -0.508 0.2794) (xy -0.5334 0.2794)
			)
			(stroke
				(width 0)
				(type default)
			)
			(fill no)
			(layer "F.CrtYd")
		)
		(pad "1" smd rect
			(at 0.40005 0 270)
			(size 0.4572 0.508)
			(layers "F.Cu" "F.Mask" "F.Paste")
			(net "P12V")
		)
		(pad "2" smd rect
			(at -0.40005 0 270)
			(size 0.4572 0.508)
			(layers "F.Cu" "F.Mask" "F.Paste")
			(net "GND")
		)
	)
	(footprint ""
		(layer "F.Cu")
		(at 26.068274 -185.521092)
		(property "Reference" "R70"
			(at -3.997198 0.128524 0)
			(unlocked yes)
			(layer "F.SilkS")
			(effects
				(font
					(size 0.7874 0.5842)
					(thickness 0.1524)
				)
				(justify left)
			)
		)
		(property "Value" ""
			(at 0 0 0)
			(layer "F.Fab")
			(effects
				(font
					(size 1.27 1.27)
				)
			)
		)
		(duplicate_pad_numbers_are_jumpers no)
		(fp_line
			(start -0.7874 -0.4064)
			(end 0.7874 -0.4064)
			(stroke
				(width 0.1524)
				(type default)
			)
			(layer "F.SilkS")
		)
		(fp_line
			(start -0.7874 0.4064)
			(end -0.7874 -0.4064)
			(stroke
				(width 0.1524)
				(type default)
			)
			(layer "F.SilkS")
		)
		(fp_line
			(start 0.7874 -0.4064)
			(end 0.7874 0.4064)
			(stroke
				(width 0.1524)
				(type default)
			)
			(layer "F.SilkS")
		)
		(fp_line
			(start 0.7874 0.4064)
			(end -0.7874 0.4064)
			(stroke
				(width 0.1524)
				(type default)
			)
			(layer "F.SilkS")
		)
		(fp_poly
			(pts
				(xy -0.508 0.2794) (xy -0.508 0.2286) (xy -0.635 0.2286) (xy -0.635 -0.254) (xy -0.5334 -0.254)
				(xy -0.5334 -0.2794) (xy 0.5334 -0.2794) (xy 0.5334 -0.254) (xy 0.635 -0.254) (xy 0.635 0.254) (xy 0.5334 0.254)
				(xy 0.5334 0.2794)
			)
			(stroke
				(width 0)
				(type default)
			)
			(fill no)
			(layer "F.CrtYd")
		)
		(pad "1" smd rect
			(at 0.40005 0)
			(size 0.4572 0.508)
			(layers "F.Cu" "F.Mask" "F.Paste")
			(net "PSU3_PS_KILL")
		)
		(pad "2" smd rect
			(at -0.40005 0)
			(size 0.4572 0.508)
			(layers "F.Cu" "F.Mask" "F.Paste")
			(net "P12V_STBY")
		)
	)
	(footprint ""
		(layer "F.Cu")
		(at 74.804524 -87.145368 90)
		(property "Reference" "C18"
			(at -4.421124 0.19177 90)
			(unlocked yes)
			(layer "F.SilkS")
			(effects
				(font
					(size 0.7874 0.5842)
					(thickness 0.1524)
				)
				(justify left)
			)
		)
		(property "Value" ""
			(at 0 0 90)
			(layer "F.Fab")
			(effects
				(font
					(size 1.27 1.27)
				)
			)
		)
		(duplicate_pad_numbers_are_jumpers no)
		(fp_line
			(start 0.7874 -0.4064)
			(end 0.7874 0.4064)
			(stroke
				(width 0.1524)
				(type default)
			)
			(layer "F.SilkS")
		)
		(fp_line
			(start -0.7874 -0.4064)
			(end 0.7874 -0.4064)
			(stroke
				(width 0.1524)
				(type default)
			)
			(layer "F.SilkS")
		)
		(fp_line
			(start 0 0.381)
			(end 0 -0.381)
			(stroke
				(width 0.1524)
				(type default)
			)
			(layer "F.SilkS")
		)
		(fp_line
			(start 0.7874 0.4064)
			(end -0.7874 0.4064)
			(stroke
				(width 0.1524)
				(type default)
			)
			(layer "F.SilkS")
		)
		(fp_line
			(start -0.7874 0.4064)
			(end -0.7874 -0.4064)
			(stroke
				(width 0.1524)
				(type default)
			)
			(layer "F.SilkS")
		)
		(fp_poly
			(pts
				(xy -0.5334 0.254) (xy -0.635 0.254) (xy -0.635 0.2286) (xy -0.635 -0.254) (xy -0.5334 -0.254) (xy -0.5334 -0.2794)
				(xy 0.5334 -0.2794) (xy 0.5334 -0.254) (xy 0.635 -0.254) (xy 0.635 0.254) (xy 0.5334 0.254) (xy 0.5334 0.2794)
				(xy -0.508 0.2794) (xy -0.5334 0.2794)
			)
			(stroke
				(width 0)
				(type default)
			)
			(fill no)
			(layer "F.CrtYd")
		)
		(pad "1" smd rect
			(at 0.40005 0 90)
			(size 0.4572 0.508)
			(layers "F.Cu" "F.Mask" "F.Paste")
			(net "P12V")
		)
		(pad "2" smd rect
			(at -0.40005 0 90)
			(size 0.4572 0.508)
			(layers "F.Cu" "F.Mask" "F.Paste")
			(net "GND")
		)
	)
	(footprint ""
		(layer "F.Cu")
		(at 40.86098 -283.09824 -90)
		(property "Reference" "R21"
			(at 0.946912 -2.85623 90)
			(unlocked yes)
			(layer "F.SilkS")
			(effects
				(font
					(size 0.7874 0.5842)
					(thickness 0.1524)
				)
				(justify left)
			)
		)
		(property "Value" ""
			(at 0 0 270)
			(layer "F.Fab")
			(effects
				(font
					(size 1.27 1.27)
				)
			)
		)
		(duplicate_pad_numbers_are_jumpers no)
		(fp_line
			(start -0.7874 0.4064)
			(end -0.7874 -0.4064)
			(stroke
				(width 0.1524)
				(type default)
			)
			(layer "F.SilkS")
		)
		(fp_line
			(start 0.7874 0.4064)
			(end -0.7874 0.4064)
			(stroke
				(width 0.1524)
				(type default)
			)
			(layer "F.SilkS")
		)
		(fp_line
			(start -0.7874 -0.4064)
			(end 0.7874 -0.4064)
			(stroke
				(width 0.1524)
				(type default)
			)
			(layer "F.SilkS")
		)
		(fp_line
			(start 0.7874 -0.4064)
			(end 0.7874 0.4064)
			(stroke
				(width 0.1524)
				(type default)
			)
			(layer "F.SilkS")
		)
		(fp_poly
			(pts
				(xy -0.508 0.2794) (xy -0.508 0.2286) (xy -0.635 0.2286) (xy -0.635 -0.254) (xy -0.5334 -0.254)
				(xy -0.5334 -0.2794) (xy 0.5334 -0.2794) (xy 0.5334 -0.254) (xy 0.635 -0.254) (xy 0.635 0.254) (xy 0.5334 0.254)
				(xy 0.5334 0.2794)
			)
			(stroke
				(width 0)
				(type default)
			)
			(fill no)
			(layer "F.CrtYd")
		)
		(pad "1" smd rect
			(at 0.40005 0 270)
			(size 0.4572 0.508)
			(layers "F.Cu" "F.Mask" "F.Paste")
			(net "PSU4_AD0")
		)
		(pad "2" smd rect
			(at -0.40005 0 270)
			(size 0.4572 0.508)
			(layers "F.Cu" "F.Mask" "F.Paste")
			(net "GND")
		)
	)
	(footprint ""
		(layer "F.Cu")
		(at 15.16507 -396.021052 180)
		(property "Reference" "R153"
			(at -1.305814 -0.218694 0)
			(unlocked yes)
			(layer "F.SilkS")
			(effects
				(font
					(size 0.7874 0.5842)
					(thickness 0.1524)
				)
				(justify left)
			)
		)
		(property "Value" ""
			(at 0 0 180)
			(layer "F.Fab")
			(effects
				(font
					(size 1.27 1.27)
				)
			)
		)
		(duplicate_pad_numbers_are_jumpers no)
		(fp_line
			(start 0.7874 0.4064)
			(end -0.7874 0.4064)
			(stroke
				(width 0.1524)
				(type default)
			)
			(layer "F.SilkS")
		)
		(fp_line
			(start 0.7874 -0.4064)
			(end 0.7874 0.4064)
			(stroke
				(width 0.1524)
				(type default)
			)
			(layer "F.SilkS")
		)
		(fp_line
			(start -0.7874 0.4064)
			(end -0.7874 -0.4064)
			(stroke
				(width 0.1524)
				(type default)
			)
			(layer "F.SilkS")
		)
		(fp_line
			(start -0.7874 -0.4064)
			(end 0.7874 -0.4064)
			(stroke
				(width 0.1524)
				(type default)
			)
			(layer "F.SilkS")
		)
		(fp_poly
			(pts
				(xy -0.508 0.2794) (xy -0.508 0.2286) (xy -0.635 0.2286) (xy -0.635 -0.254) (xy -0.5334 -0.254)
				(xy -0.5334 -0.2794) (xy 0.5334 -0.2794) (xy 0.5334 -0.254) (xy 0.635 -0.254) (xy 0.635 0.254) (xy 0.5334 0.254)
				(xy 0.5334 0.2794)
			)
			(stroke
				(width 0)
				(type default)
			)
			(fill no)
			(layer "F.CrtYd")
		)
		(pad "1" smd rect
			(at 0.40005 0 180)
			(size 0.4572 0.508)
			(layers "F.Cu" "F.Mask" "F.Paste")
			(net "GND")
		)
		(pad "2" smd rect
			(at -0.40005 0 180)
			(size 0.4572 0.508)
			(layers "F.Cu" "F.Mask" "F.Paste")
			(net "N42132358")
		)
	)
	(footprint ""
		(layer "F.Cu")
		(at 13.451332 -339.764624 -90)
		(property "Reference" "R41"
			(at -1.347724 -0.199136 90)
			(unlocked yes)
			(layer "F.SilkS")
			(effects
				(font
					(size 0.7874 0.5842)
					(thickness 0.1524)
				)
				(justify left)
			)
		)
		(property "Value" ""
			(at 0 0 270)
			(layer "F.Fab")
			(effects
				(font
					(size 1.27 1.27)
				)
			)
		)
		(duplicate_pad_numbers_are_jumpers no)
		(fp_line
			(start -0.7874 0.4064)
			(end -0.7874 -0.4064)
			(stroke
				(width 0.1524)
				(type default)
			)
			(layer "F.SilkS")
		)
		(fp_line
			(start 0.7874 0.4064)
			(end -0.7874 0.4064)
			(stroke
				(width 0.1524)
				(type default)
			)
			(layer "F.SilkS")
		)
		(fp_line
			(start -0.7874 -0.4064)
			(end 0.7874 -0.4064)
			(stroke
				(width 0.1524)
				(type default)
			)
			(layer "F.SilkS")
		)
		(fp_line
			(start 0.7874 -0.4064)
			(end 0.7874 0.4064)
			(stroke
				(width 0.1524)
				(type default)
			)
			(layer "F.SilkS")
		)
		(fp_poly
			(pts
				(xy -0.508 0.2794) (xy -0.508 0.2286) (xy -0.635 0.2286) (xy -0.635 -0.254) (xy -0.5334 -0.254)
				(xy -0.5334 -0.2794) (xy 0.5334 -0.2794) (xy 0.5334 -0.254) (xy 0.635 -0.254) (xy 0.635 0.254) (xy 0.5334 0.254)
				(xy 0.5334 0.2794)
			)
			(stroke
				(width 0)
				(type default)
			)
			(fill no)
			(layer "F.CrtYd")
		)
		(pad "1" smd rect
			(at 0.40005 0 270)
			(size 0.4572 0.508)
			(layers "F.Cu" "F.Mask" "F.Paste")
			(net "P3V3")
		)
		(pad "2" smd rect
			(at -0.40005 0 270)
			(size 0.4572 0.508)
			(layers "F.Cu" "F.Mask" "F.Paste")
			(net "FRU_WP")
		)
	)
	(footprint ""
		(layer "F.Cu")
		(at 72.611996 -237.708694 -90)
		(property "Reference" "C38"
			(at 0.73406 -3.85445 90)
			(unlocked yes)
			(layer "F.SilkS")
			(effects
				(font
					(size 0.7874 0.5842)
					(thickness 0.1524)
				)
				(justify left)
			)
		)
		(property "Value" ""
			(at 0 0 270)
			(layer "F.Fab")
			(effects
				(font
					(size 1.27 1.27)
				)
			)
		)
		(duplicate_pad_numbers_are_jumpers no)
		(fp_line
			(start -0.7874 0.4064)
			(end -0.7874 -0.4064)
			(stroke
				(width 0.1524)
				(type default)
			)
			(layer "F.SilkS")
		)
		(fp_line
			(start 0.7874 0.4064)
			(end -0.7874 0.4064)
			(stroke
				(width 0.1524)
				(type default)
			)
			(layer "F.SilkS")
		)
		(fp_line
			(start 0 0.381)
			(end 0 -0.381)
			(stroke
				(width 0.1524)
				(type default)
			)
			(layer "F.SilkS")
		)
		(fp_line
			(start -0.7874 -0.4064)
			(end 0.7874 -0.4064)
			(stroke
				(width 0.1524)
				(type default)
			)
			(layer "F.SilkS")
		)
		(fp_line
			(start 0.7874 -0.4064)
			(end 0.7874 0.4064)
			(stroke
				(width 0.1524)
				(type default)
			)
			(layer "F.SilkS")
		)
		(fp_poly
			(pts
				(xy -0.5334 0.254) (xy -0.635 0.254) (xy -0.635 0.2286) (xy -0.635 -0.254) (xy -0.5334 -0.254) (xy -0.5334 -0.2794)
				(xy 0.5334 -0.2794) (xy 0.5334 -0.254) (xy 0.635 -0.254) (xy 0.635 0.254) (xy 0.5334 0.254) (xy 0.5334 0.2794)
				(xy -0.508 0.2794) (xy -0.5334 0.2794)
			)
			(stroke
				(width 0)
				(type default)
			)
			(fill no)
			(layer "F.CrtYd")
		)
		(pad "1" smd rect
			(at 0.40005 0 270)
			(size 0.4572 0.508)
			(layers "F.Cu" "F.Mask" "F.Paste")
			(net "P12V")
		)
		(pad "2" smd rect
			(at -0.40005 0 270)
			(size 0.4572 0.508)
			(layers "F.Cu" "F.Mask" "F.Paste")
			(net "GND")
		)
	)
	(footprint ""
		(layer "F.Cu")
		(at 73.63333 -87.145368 90)
		(property "Reference" "C19"
			(at -4.367022 0.092202 90)
			(unlocked yes)
			(layer "F.SilkS")
			(effects
				(font
					(size 0.7874 0.5842)
					(thickness 0.1524)
				)
				(justify left)
			)
		)
		(property "Value" ""
			(at 0 0 90)
			(layer "F.Fab")
			(effects
				(font
					(size 1.27 1.27)
				)
			)
		)
		(duplicate_pad_numbers_are_jumpers no)
		(fp_line
			(start 0.7874 -0.4064)
			(end 0.7874 0.4064)
			(stroke
				(width 0.1524)
				(type default)
			)
			(layer "F.SilkS")
		)
		(fp_line
			(start -0.7874 -0.4064)
			(end 0.7874 -0.4064)
			(stroke
				(width 0.1524)
				(type default)
			)
			(layer "F.SilkS")
		)
		(fp_line
			(start 0 0.381)
			(end 0 -0.381)
			(stroke
				(width 0.1524)
				(type default)
			)
			(layer "F.SilkS")
		)
		(fp_line
			(start 0.7874 0.4064)
			(end -0.7874 0.4064)
			(stroke
				(width 0.1524)
				(type default)
			)
			(layer "F.SilkS")
		)
		(fp_line
			(start -0.7874 0.4064)
			(end -0.7874 -0.4064)
			(stroke
				(width 0.1524)
				(type default)
			)
			(layer "F.SilkS")
		)
		(fp_poly
			(pts
				(xy -0.5334 0.254) (xy -0.635 0.254) (xy -0.635 0.2286) (xy -0.635 -0.254) (xy -0.5334 -0.254) (xy -0.5334 -0.2794)
				(xy 0.5334 -0.2794) (xy 0.5334 -0.254) (xy 0.635 -0.254) (xy 0.635 0.254) (xy 0.5334 0.254) (xy 0.5334 0.2794)
				(xy -0.508 0.2794) (xy -0.5334 0.2794)
			)
			(stroke
				(width 0)
				(type default)
			)
			(fill no)
			(layer "F.CrtYd")
		)
		(pad "1" smd rect
			(at 0.40005 0 90)
			(size 0.4572 0.508)
			(layers "F.Cu" "F.Mask" "F.Paste")
			(net "P12V")
		)
		(pad "2" smd rect
			(at -0.40005 0 90)
			(size 0.4572 0.508)
			(layers "F.Cu" "F.Mask" "F.Paste")
			(net "GND")
		)
	)
	(footprint ""
		(layer "F.Cu")
		(at 72.802242 -459.732634 -90)
		(property "Reference" "C72"
			(at -2.962656 -0.27813 90)
			(unlocked yes)
			(layer "F.SilkS")
			(effects
				(font
					(size 0.7874 0.5842)
					(thickness 0.1524)
				)
				(justify left)
			)
		)
		(property "Value" ""
			(at 0 0 270)
			(layer "F.Fab")
			(effects
				(font
					(size 1.27 1.27)
				)
			)
		)
		(duplicate_pad_numbers_are_jumpers no)
		(fp_line
			(start -0.7874 0.4064)
			(end -0.7874 -0.4064)
			(stroke
				(width 0.1524)
				(type default)
			)
			(layer "F.SilkS")
		)
		(fp_line
			(start 0.7874 0.4064)
			(end -0.7874 0.4064)
			(stroke
				(width 0.1524)
				(type default)
			)
			(layer "F.SilkS")
		)
		(fp_line
			(start 0 0.381)
			(end 0 -0.381)
			(stroke
				(width 0.1524)
				(type default)
			)
			(layer "F.SilkS")
		)
		(fp_line
			(start -0.7874 -0.4064)
			(end 0.7874 -0.4064)
			(stroke
				(width 0.1524)
				(type default)
			)
			(layer "F.SilkS")
		)
		(fp_line
			(start 0.7874 -0.4064)
			(end 0.7874 0.4064)
			(stroke
				(width 0.1524)
				(type default)
			)
			(layer "F.SilkS")
		)
		(fp_poly
			(pts
				(xy -0.5334 0.254) (xy -0.635 0.254) (xy -0.635 0.2286) (xy -0.635 -0.254) (xy -0.5334 -0.254) (xy -0.5334 -0.2794)
				(xy 0.5334 -0.2794) (xy 0.5334 -0.254) (xy 0.635 -0.254) (xy 0.635 0.254) (xy 0.5334 0.254) (xy 0.5334 0.2794)
				(xy -0.508 0.2794) (xy -0.5334 0.2794)
			)
			(stroke
				(width 0)
				(type default)
			)
			(fill no)
			(layer "F.CrtYd")
		)
		(pad "1" smd rect
			(at 0.40005 0 270)
			(size 0.4572 0.508)
			(layers "F.Cu" "F.Mask" "F.Paste")
			(net "P12V")
		)
		(pad "2" smd rect
			(at -0.40005 0 270)
			(size 0.4572 0.508)
			(layers "F.Cu" "F.Mask" "F.Paste")
			(net "GND")
		)
	)
)
